(kicad_pcb
	(version 20260206)
	(generator "pcbnew")
	(generator_version "10.0")
	(general
		(thickness 1.6)
		(legacy_teardrops no)
	)
	(paper "A4")
	(title_block
		(title "v2-tray-backplane — ms_tbp_v2.brd")
		(comment 1 "Open CloudServer (Microsoft) / footprints 51-51 of 164")
	)
	(layers
		(0 "F.Cu" signal "TOP")
		(4 "In1.Cu" signal "LYR2")
		(6 "In2.Cu" signal "LYR3")
		(8 "In3.Cu" signal "LYR4")
		(10 "In4.Cu" signal "LYR5")
		(12 "In5.Cu" signal "LYR6")
		(14 "In6.Cu" signal "LYR7")
		(2 "B.Cu" signal "BOTTOM")
		(9 "F.Adhes" user "F.Adhesive")
		(11 "B.Adhes" user "B.Adhesive")
		(13 "F.Paste" user "Package Geometry/Pastemask Top")
		(15 "B.Paste" user "Package Geometry/Pastemask Bottom")
		(5 "F.SilkS" user "Ref Des/Silkscreen Top")
		(7 "B.SilkS" user "Ref Des/Silkscreen Bottom")
		(1 "F.Mask" user "Board Geometry/Soldermask Top")
		(3 "B.Mask" user "Board Geometry/Soldermask Bottom")
		(17 "Dwgs.User" user "User.Drawings")
		(19 "Cmts.User" user "User.Comments")
		(21 "Eco1.User" user "User.Eco1")
		(23 "Eco2.User" user "User.Eco2")
		(25 "Edge.Cuts" user "Board Geometry/Outline")
		(27 "Margin" user)
		(31 "F.CrtYd" user "Package Geometry/Place Bound Top")
		(29 "B.CrtYd" user "Package Geometry/Place Bound Bottom")
		(35 "F.Fab" user "Ref Des/Assembly Top")
		(33 "B.Fab" user "Ref Des/Assembly Bottom")
	)
	(footprint ""
		(layer "F.Cu")
		(at -331.47 18.8468)
		(property "Reference" "R6"
			(at 1.94564 -0.0381 0)
			(unlocked yes)
			(layer "F.SilkS")
			(effects
				(font
					(size 0.762 0.5334)
					(thickness 0.1016)
				)
			)
		)
		(property "Value" ""
			(at 0 0 0)
			(layer "F.Fab")
			(effects
				(font
					(size 1.27 1.27)
				)
			)
		)
		(duplicate_pad_numbers_are_jumpers no)
		(fp_line
			(start 0 -0.381)
			(end 0 0.381)
			(stroke
				(width 0.127)
				(type default)
			)
			(layer "F.SilkS")
		)
		(fp_poly
			(pts
				(xy 1.255601 0.6564) (xy -1.255601 0.6564) (xy -1.255601 -0.656399) (xy 1.255601 -0.656399)
			)
			(stroke
				(width 0)
				(type default)
			)
			(fill no)
			(layer "F.CrtYd")
		)
		(fp_line
			(start -0.800001 -0.399999)
			(end -0.800001 0.399999)
			(stroke
				(width 0.1)
				(type default)
			)
			(layer "F.Fab")
		)
		(fp_line
			(start -0.800001 0.399999)
			(end 0.800001 0.399999)
			(stroke
				(width 0.1)
				(type default)
			)
			(layer "F.Fab")
		)
		(fp_line
			(start 0.800001 -0.399999)
			(end -0.800001 -0.399999)
			(stroke
				(width 0.1)
				(type default)
			)
			(layer "F.Fab")
		)
		(fp_line
			(start 0.800001 0.399999)
			(end 0.800001 -0.399999)
			(stroke
				(width 0.1)
				(type default)
			)
			(layer "F.Fab")
		)
		(pad "1" smd rect
			(at -0.650001 0)
			(size 0.7112 0.8128)
			(layers "F.Cu" "F.Mask" "F.Paste")
			(net "P3V3_B1_QSFP")
		)
		(pad "2" smd rect
			(at 0.650001 0 180)
			(size 0.7112 0.8128)
			(layers "F.Cu" "F.Mask" "F.Paste")
			(net "SKU_B1_ID2")
		)
	)
)
